(kicad_pcb
	(version 20260206)
	(generator "pcbnew")
	(generator_version "10.0")
	(general
		(thickness 1.6)
		(legacy_teardrops no)
	)
	(paper "A4")
	(title_block
		(title "03242023_DA0F0TMBIJ0_F0T_Motherboard_J_brd_V01_OCP.brd")
		(comment 1 "Grand Teton / footprints 3953-3956 of 6105")
	)
	(layers
		(0 "F.Cu" signal "TOP")
		(4 "In1.Cu" signal "GND")
		(6 "In2.Cu" signal "IN1")
		(8 "In3.Cu" signal "GND1")
		(10 "In4.Cu" signal "IN2")
		(12 "In5.Cu" signal "GND2")
		(14 "In6.Cu" signal "IN3")
		(16 "In7.Cu" signal "GND3")
		(18 "In8.Cu" signal "VCC")
		(20 "In9.Cu" signal "VCC1")
		(22 "In10.Cu" signal "GND4")
		(24 "In11.Cu" signal "IN4")
		(26 "In12.Cu" signal "GND5")
		(28 "In13.Cu" signal "IN5")
		(30 "In14.Cu" signal "GND6")
		(32 "In15.Cu" signal "IN6")
		(34 "In16.Cu" signal "GND7")
		(2 "B.Cu" signal "BOTTOM")
		(9 "F.Adhes" user "F.Adhesive")
		(11 "B.Adhes" user "B.Adhesive")
		(13 "F.Paste" user "Package Geometry/Pastemask Top")
		(15 "B.Paste" user "Package Geometry/Pastemask Bottom")
		(5 "F.SilkS" user "Ref Des/Silkscreen Top")
		(7 "B.SilkS" user "Ref Des/Silkscreen Bottom")
		(1 "F.Mask" user "Board Geometry/Soldermask Top")
		(3 "B.Mask" user "Board Geometry/Soldermask Bottom")
		(17 "Dwgs.User" user "User.Drawings")
		(19 "Cmts.User" user "User.Comments")
		(21 "Eco1.User" user "User.Eco1")
		(23 "Eco2.User" user "User.Eco2")
		(25 "Edge.Cuts" user "Board Geometry/Outline")
		(27 "Margin" user)
		(31 "F.CrtYd" user "Package Geometry/Place Bound Top")
		(29 "B.CrtYd" user "Package Geometry/Place Bound Bottom")
		(35 "F.Fab" user "Ref Des/Assembly Top")
		(33 "B.Fab" user "Ref Des/Assembly Bottom")
	)
	(footprint ""
		(layer "F.Cu")
		(at 240.61674 -253.345188 180)
		(property "Reference" "R4081"
			(at 0 0 180)
			(layer "F.SilkS")
			(hide yes)
			(effects
				(font
					(size 1.27 1.27)
				)
			)
		)
		(property "Value" ""
			(at 0 0 180)
			(layer "F.Fab")
			(effects
				(font
					(size 1.27 1.27)
				)
			)
		)
		(duplicate_pad_numbers_are_jumpers no)
		(fp_line
			(start 0.7874 0.4064)
			(end -0.7874 0.4064)
			(stroke
				(width 0.1524)
				(type default)
			)
			(layer "F.SilkS")
		)
		(fp_line
			(start 0.7874 -0.4064)
			(end 0.7874 0.4064)
			(stroke
				(width 0.1524)
				(type default)
			)
			(layer "F.SilkS")
		)
		(fp_line
			(start -0.7874 0.4064)
			(end -0.7874 -0.4064)
			(stroke
				(width 0.1524)
				(type default)
			)
			(layer "F.SilkS")
		)
		(fp_line
			(start -0.7874 -0.4064)
			(end 0.7874 -0.4064)
			(stroke
				(width 0.1524)
				(type default)
			)
			(layer "F.SilkS")
		)
		(fp_line
			(start 0.67945 0.3048)
			(end 0.120396 0.3048)
			(stroke
				(width 0.1)
				(type default)
			)
			(layer "F.Fab")
		)
		(fp_line
			(start 0.67945 -0.3048)
			(end 0.67945 0.3048)
			(stroke
				(width 0.1)
				(type default)
			)
			(layer "F.Fab")
		)
		(fp_line
			(start 0.12065 -0.2794)
			(end 0.12065 -0.3048)
			(stroke
				(width 0.1)
				(type default)
			)
			(layer "F.Fab")
		)
		(fp_line
			(start 0.12065 -0.3048)
			(end 0.67945 -0.3048)
			(stroke
				(width 0.1)
				(type default)
			)
			(layer "F.Fab")
		)
		(fp_line
			(start 0.120396 0.3048)
			(end 0.120396 0.2794)
			(stroke
				(width 0.1)
				(type default)
			)
			(layer "F.Fab")
		)
		(fp_line
			(start 0.120396 0.2794)
			(end -0.12065 0.2794)
			(stroke
				(width 0.1)
				(type default)
			)
			(layer "F.Fab")
		)
		(fp_line
			(start -0.12065 0.3048)
			(end -0.67945 0.3048)
			(stroke
				(width 0.1)
				(type default)
			)
			(layer "F.Fab")
		)
		(fp_line
			(start -0.12065 0.2794)
			(end -0.12065 0.3048)
			(stroke
				(width 0.1)
				(type default)
			)
			(layer "F.Fab")
		)
		(fp_line
			(start -0.12065 -0.2794)
			(end 0.12065 -0.2794)
			(stroke
				(width 0.1)
				(type default)
			)
			(layer "F.Fab")
		)
		(fp_line
			(start -0.12065 -0.305054)
			(end -0.12065 -0.2794)
			(stroke
				(width 0.1)
				(type default)
			)
			(layer "F.Fab")
		)
		(fp_line
			(start -0.67945 0.3048)
			(end -0.67945 -0.305054)
			(stroke
				(width 0.1)
				(type default)
			)
			(layer "F.Fab")
		)
		(fp_line
			(start -0.67945 -0.305054)
			(end -0.12065 -0.305054)
			(stroke
				(width 0.1)
				(type default)
			)
			(layer "F.Fab")
		)
		(pad "1" smd circle
			(at -0.40005 0 180)
			(size 0 0)
			(layers "F.Cu" "F.Mask" "F.Paste")
			(net "P3V3_AUX")
		)
		(pad "2" smd circle
			(at 0.40005 0 180)
			(size 0 0)
			(layers "F.Cu" "F.Mask" "F.Paste")
			(net "CLK_GEN2_SMB_SADR")
		)
	)
	(footprint ""
		(layer "F.Cu")
		(at 353.0981 -333.716122)
		(property "Reference" "PU12_P0_2"
			(at -2.87528 -6.13537 0)
			(unlocked yes)
			(layer "F.SilkS")
			(effects
				(font
					(size 0.7874 0.5842)
					(thickness 0.1524)
				)
				(justify left)
			)
		)
		(property "Value" ""
			(at 0 0 0)
			(layer "F.Fab")
			(effects
				(font
					(size 1.27 1.27)
				)
			)
		)
		(duplicate_pad_numbers_are_jumpers no)
		(fp_line
			(start -2.500122 -2.999994)
			(end -2.24409 -2.999994)
			(stroke
				(width 0.1524)
				(type default)
			)
			(layer "F.SilkS")
		)
		(fp_line
			(start -2.500122 -2.529078)
			(end -2.500122 -2.999994)
			(stroke
				(width 0.1524)
				(type default)
			)
			(layer "F.SilkS")
		)
		(fp_line
			(start -2.500122 0.6604)
			(end -2.500122 0.229108)
			(stroke
				(width 0.1524)
				(type default)
			)
			(layer "F.SilkS")
		)
		(fp_line
			(start -2.500122 2.999994)
			(end -2.500122 2.339594)
			(stroke
				(width 0.1524)
				(type default)
			)
			(layer "F.SilkS")
		)
		(fp_line
			(start -2.2987 2.999994)
			(end -2.500122 2.999994)
			(stroke
				(width 0.1524)
				(type default)
			)
			(layer "F.SilkS")
		)
		(fp_line
			(start 2.31394 -2.999994)
			(end 2.500122 -2.999994)
			(stroke
				(width 0.1524)
				(type default)
			)
			(layer "F.SilkS")
		)
		(fp_line
			(start 2.500122 -2.999994)
			(end 2.500122 -2.44348)
			(stroke
				(width 0.1524)
				(type default)
			)
			(layer "F.SilkS")
		)
		(fp_line
			(start 2.500122 2.339594)
			(end 2.500122 2.999994)
			(stroke
				(width 0.1524)
				(type default)
			)
			(layer "F.SilkS")
		)
		(fp_line
			(start 2.500122 2.999994)
			(end 2.2987 2.999994)
			(stroke
				(width 0.1524)
				(type default)
			)
			(layer "F.SilkS")
		)
		(fp_poly
			(pts
				(xy -2.210308 -3.613658) (xy -2.718308 -2.597658) (xy -3.226308 -3.613658)
			)
			(stroke
				(width 0)
				(type default)
			)
			(fill yes)
			(layer "F.SilkS")
		)
		(fp_line
			(start -2.500122 -2.999994)
			(end 2.500122 -2.999994)
			(stroke
				(width 0.1)
				(type default)
			)
			(layer "F.Fab")
		)
		(fp_line
			(start -2.500122 2.999994)
			(end -2.500122 -2.999994)
			(stroke
				(width 0.1)
				(type default)
			)
			(layer "F.Fab")
		)
		(fp_line
			(start 2.500122 -2.999994)
			(end 2.500122 2.999994)
			(stroke
				(width 0.1)
				(type default)
			)
			(layer "F.Fab")
		)
		(fp_line
			(start 2.500122 2.999994)
			(end -2.500122 2.999994)
			(stroke
				(width 0.1)
				(type default)
			)
			(layer "F.Fab")
		)
		(fp_poly
			(pts
				(xy -4.218432 -2.783078) (xy -4.218432 -1.767078) (xy -3.202432 -2.275078)
			)
			(stroke
				(width 0)
				(type default)
			)
			(fill yes)
			(layer "F.Fab")
		)
		(pad "1" smd rect
			(at -2.400046 -2.275078 90)
			(size 0.2286 0.6096)
			(layers "F.Cu" "F.Mask" "F.Paste")
			(net "PVCCIN_CPU0_VOS2")
		)
		(pad "2" smd rect
			(at -2.400046 -1.82499 90)
			(size 0.2286 0.6096)
			(layers "F.Cu" "F.Mask" "F.Paste")
			(net "GND")
		)
		(pad "3" smd rect
			(at -2.400046 -1.374902 90)
			(size 0.2286 0.6096)
			(layers "F.Cu" "F.Mask" "F.Paste")
			(net "PVCCIN_CPU0_VDD2")
		)
		(pad "4" smd rect
			(at -2.400046 -0.925068 90)
			(size 0.2286 0.6096)
			(layers "F.Cu" "F.Mask" "F.Paste")
			(net "PVCCIN_CPU0_PVCC")
		)
		(pad "5" smd rect
			(at -2.400046 -0.47498 90)
			(size 0.2286 0.6096)
			(layers "F.Cu" "F.Mask" "F.Paste")
			(net "GND")
		)
		(pad "6" smd rect
			(at -2.400046 -0.024892 90)
			(size 0.2286 0.6096)
			(layers "F.Cu" "F.Mask" "F.Paste")
			(net "Net_8547")
		)
		(pad "7_9-20_24" smd circle
			(at 0 1.150112 90)
			(size 0 0)
			(layers "F.Cu" "F.Mask" "F.Paste")
			(net "GND")
		)
		(pad "10_19" smd rect
			(at 0 2.899918 90)
			(size 0.6096 4.318)
			(layers "F.Cu" "F.Mask" "F.Paste")
			(net "SW_PVCCIN_CPU0_SW2")
		)
		(pad "25_29" smd rect
			(at 1.549908 -1.279906 270)
			(size 2.0574 2.3114)
			(layers "F.Cu" "F.Mask" "F.Paste")
			(net "SW_P12V_PVCCIN_CPU0_FLT")
		)
		(pad "30" smd rect
			(at 2.05994 -2.899918)
			(size 0.2286 0.6096)
			(layers "F.Cu" "F.Mask" "F.Paste")
			(net "SW_P12V_PVCCIN_CPU0_FLT")
		)
		(pad "31" smd rect
			(at 1.610106 -2.899918)
			(size 0.2286 0.6096)
			(layers "F.Cu" "F.Mask" "F.Paste")
			(net "Net_8548")
		)
		(pad "32" smd rect
			(at 1.160018 -2.899918)
			(size 0.2286 0.6096)
			(layers "F.Cu" "F.Mask" "F.Paste")
			(net "SW_PVCCIN_CPU0_BOOTR2")
		)
		(pad "33" smd rect
			(at 0.70993 -2.899918)
			(size 0.2286 0.6096)
			(layers "F.Cu" "F.Mask" "F.Paste")
			(net "SW_PVCCIN_CPU0_BOOT2")
		)
		(pad "34" smd rect
			(at 0.260096 -2.899918)
			(size 0.2286 0.6096)
			(layers "F.Cu" "F.Mask" "F.Paste")
			(net "PVCCIN_CPU0_PWM2")
		)
		(pad "35" smd rect
			(at -0.189992 -2.899918)
			(size 0.2286 0.6096)
			(layers "F.Cu" "F.Mask" "F.Paste")
			(net "PVCCIN_CPU0_VDD2")
		)
		(pad "36" smd rect
			(at -0.64008 -2.899918)
			(size 0.2286 0.6096)
			(layers "F.Cu" "F.Mask" "F.Paste")
			(net "PVCCIN_CPU0_ATSEN")
		)
		(pad "37" smd rect
			(at -1.089914 -2.899918)
			(size 0.2286 0.6096)
			(layers "F.Cu" "F.Mask" "F.Paste")
			(net "PVCCIN_CPU0_LSET2")
		)
		(pad "38" smd rect
			(at -1.540002 -2.899918)
			(size 0.2286 0.6096)
			(layers "F.Cu" "F.Mask" "F.Paste")
			(net "PVCCIN_CPU0_IMON2")
		)
		(pad "39" smd rect
			(at -1.99009 -2.899918)
			(size 0.2286 0.6096)
			(layers "F.Cu" "F.Mask" "F.Paste")
			(net "PVCCIN_CPU0_VREF")
		)
		(pad "40" smd rect
			(at -0.87503 -1.27508)
			(size 1.7526 1.9558)
			(layers "F.Cu" "F.Mask" "F.Paste")
			(net "GND")
		)
		(pad "41" smd rect
			(at -1.525016 0.249936 270)
			(size 0.3048 0.4572)
			(layers "F.Cu" "F.Mask" "F.Paste")
			(net "Net_8546")
		)
		(zone
			(layer "F.Cu")
			(hatch none 0.5)
			(connect_pads
				(clearance 0)
			)
			(min_thickness 0.25)
			(keepout
				(tracks not_allowed)
				(vias allowed)
				(pads allowed)
				(copperpour not_allowed)
				(footprints allowed)
			)
			(placement
				(enabled no)
				(sheetname "")
			)
			(fill
				(thermal_gap 0.5)
				(thermal_bridge_width 0.5)
				(island_removal_mode 0)
			)
			(polygon
				(pts
					(xy 350.597978 -330.716128) (xy 350.597978 -331.465428) (xy 355.598222 -331.465428) (xy 355.598222 -330.716128)
					(xy 355.3079 -330.716128) (xy 355.3079 -331.171804) (xy 350.8883 -331.171804) (xy 350.8883 -330.716128)
				)
			)
		)
		(zone
			(layer "F.Cu")
			(hatch none 0.5)
			(connect_pads
				(clearance 0)
			)
			(min_thickness 0.25)
			(keepout
				(tracks not_allowed)
				(vias allowed)
				(pads allowed)
				(copperpour not_allowed)
				(footprints allowed)
			)
			(placement
				(enabled no)
				(sheetname "")
			)
			(fill
				(thermal_gap 0.5)
				(thermal_bridge_width 0.5)
				(island_removal_mode 0)
			)
			(polygon
				(pts
					(xy 351.053654 -334.038448) (xy 351.29597 -334.038448) (xy 351.29597 -333.962502) (xy 351.81794 -333.962502)
					(xy 351.81794 -333.855568) (xy 351.92462 -333.855568) (xy 351.92462 -333.789528) (xy 351.99066 -333.789528)
					(xy 351.99066 -333.647288) (xy 352.147378 -333.647288) (xy 352.147378 -332.966822) (xy 350.597978 -332.966822)
					(xy 350.597978 -333.423514) (xy 351.293684 -333.423514) (xy 351.293684 -333.262986) (xy 351.852484 -333.262986)
					(xy 351.852484 -333.669386) (xy 351.293684 -333.669386) (xy 351.293684 -333.448914) (xy 350.597978 -333.448914)
					(xy 350.597978 -333.575914) (xy 351.053654 -333.575914)
				)
			)
		)
	)
	(footprint ""
		(layer "F.Cu")
		(at 129.46888 -106.898948)
		(property "Reference" "R4409"
			(at 0 0 0)
			(layer "F.SilkS")
			(hide yes)
			(effects
				(font
					(size 1.27 1.27)
				)
			)
		)
		(property "Value" ""
			(at 0 0 0)
			(layer "F.Fab")
			(effects
				(font
					(size 1.27 1.27)
				)
			)
		)
		(duplicate_pad_numbers_are_jumpers no)
		(fp_line
			(start -0.7874 -0.4064)
			(end 0.7874 -0.4064)
			(stroke
				(width 0.1524)
				(type default)
			)
			(layer "F.SilkS")
		)
		(fp_line
			(start -0.7874 0.4064)
			(end -0.7874 -0.4064)
			(stroke
				(width 0.1524)
				(type default)
			)
			(layer "F.SilkS")
		)
		(fp_line
			(start 0.7874 -0.4064)
			(end 0.7874 0.4064)
			(stroke
				(width 0.1524)
				(type default)
			)
			(layer "F.SilkS")
		)
		(fp_line
			(start 0.7874 0.4064)
			(end -0.7874 0.4064)
			(stroke
				(width 0.1524)
				(type default)
			)
			(layer "F.SilkS")
		)
		(fp_line
			(start -0.67945 -0.305054)
			(end -0.12065 -0.305054)
			(stroke
				(width 0.1)
				(type default)
			)
			(layer "F.Fab")
		)
		(fp_line
			(start -0.67945 0.3048)
			(end -0.67945 -0.305054)
			(stroke
				(width 0.1)
				(type default)
			)
			(layer "F.Fab")
		)
		(fp_line
			(start -0.12065 -0.305054)
			(end -0.12065 -0.2794)
			(stroke
				(width 0.1)
				(type default)
			)
			(layer "F.Fab")
		)
		(fp_line
			(start -0.12065 -0.2794)
			(end 0.12065 -0.2794)
			(stroke
				(width 0.1)
				(type default)
			)
			(layer "F.Fab")
		)
		(fp_line
			(start -0.12065 0.2794)
			(end -0.12065 0.3048)
			(stroke
				(width 0.1)
				(type default)
			)
			(layer "F.Fab")
		)
		(fp_line
			(start -0.12065 0.3048)
			(end -0.67945 0.3048)
			(stroke
				(width 0.1)
				(type default)
			)
			(layer "F.Fab")
		)
		(fp_line
			(start 0.120396 0.2794)
			(end -0.12065 0.2794)
			(stroke
				(width 0.1)
				(type default)
			)
			(layer "F.Fab")
		)
		(fp_line
			(start 0.120396 0.3048)
			(end 0.120396 0.2794)
			(stroke
				(width 0.1)
				(type default)
			)
			(layer "F.Fab")
		)
		(fp_line
			(start 0.12065 -0.3048)
			(end 0.67945 -0.3048)
			(stroke
				(width 0.1)
				(type default)
			)
			(layer "F.Fab")
		)
		(fp_line
			(start 0.12065 -0.2794)
			(end 0.12065 -0.3048)
			(stroke
				(width 0.1)
				(type default)
			)
			(layer "F.Fab")
		)
		(fp_line
			(start 0.67945 -0.3048)
			(end 0.67945 0.3048)
			(stroke
				(width 0.1)
				(type default)
			)
			(layer "F.Fab")
		)
		(fp_line
			(start 0.67945 0.3048)
			(end 0.120396 0.3048)
			(stroke
				(width 0.1)
				(type default)
			)
			(layer "F.Fab")
		)
		(pad "1" smd circle
			(at -0.40005 0)
			(size 0 0)
			(layers "F.Cu" "F.Mask" "F.Paste")
			(net "H_CPU0_MEMTRIP")
		)
		(pad "2" smd circle
			(at 0.40005 0)
			(size 0 0)
			(layers "F.Cu" "F.Mask" "F.Paste")
			(net "H_CPU0_MEMTRIP_R")
		)
	)
	(footprint ""
		(layer "F.Cu")
		(at 205.397608 -401.775422 180)
		(property "Reference" "PR3915"
			(at 0 0 180)
			(layer "F.SilkS")
			(hide yes)
			(effects
				(font
					(size 1.27 1.27)
				)
			)
		)
		(property "Value" ""
			(at 0 0 180)
			(layer "F.Fab")
			(effects
				(font
					(size 1.27 1.27)
				)
			)
		)
		(duplicate_pad_numbers_are_jumpers no)
		(fp_line
			(start 0.7874 0.4064)
			(end -0.7874 0.4064)
			(stroke
				(width 0.1524)
				(type default)
			)
			(layer "F.SilkS")
		)
		(fp_line
			(start 0.7874 -0.4064)
			(end 0.7874 0.4064)
			(stroke
				(width 0.1524)
				(type default)
			)
			(layer "F.SilkS")
		)
		(fp_line
			(start -0.7874 0.4064)
			(end -0.7874 -0.4064)
			(stroke
				(width 0.1524)
				(type default)
			)
			(layer "F.SilkS")
		)
		(fp_line
			(start -0.7874 -0.4064)
			(end 0.7874 -0.4064)
			(stroke
				(width 0.1524)
				(type default)
			)
			(layer "F.SilkS")
		)
		(fp_line
			(start 0.67945 0.3048)
			(end 0.120396 0.3048)
			(stroke
				(width 0.1)
				(type default)
			)
			(layer "F.Fab")
		)
		(fp_line
			(start 0.67945 -0.3048)
			(end 0.67945 0.3048)
			(stroke
				(width 0.1)
				(type default)
			)
			(layer "F.Fab")
		)
		(fp_line
			(start 0.12065 -0.2794)
			(end 0.12065 -0.3048)
			(stroke
				(width 0.1)
				(type default)
			)
			(layer "F.Fab")
		)
		(fp_line
			(start 0.12065 -0.3048)
			(end 0.67945 -0.3048)
			(stroke
				(width 0.1)
				(type default)
			)
			(layer "F.Fab")
		)
		(fp_line
			(start 0.120396 0.3048)
			(end 0.120396 0.2794)
			(stroke
				(width 0.1)
				(type default)
			)
			(layer "F.Fab")
		)
		(fp_line
			(start 0.120396 0.2794)
			(end -0.12065 0.2794)
			(stroke
				(width 0.1)
				(type default)
			)
			(layer "F.Fab")
		)
		(fp_line
			(start -0.12065 0.3048)
			(end -0.67945 0.3048)
			(stroke
				(width 0.1)
				(type default)
			)
			(layer "F.Fab")
		)
		(fp_line
			(start -0.12065 0.2794)
			(end -0.12065 0.3048)
			(stroke
				(width 0.1)
				(type default)
			)
			(layer "F.Fab")
		)
		(fp_line
			(start -0.12065 -0.2794)
			(end 0.12065 -0.2794)
			(stroke
				(width 0.1)
				(type default)
			)
			(layer "F.Fab")
		)
		(fp_line
			(start -0.12065 -0.305054)
			(end -0.12065 -0.2794)
			(stroke
				(width 0.1)
				(type default)
			)
			(layer "F.Fab")
		)
		(fp_line
			(start -0.67945 0.3048)
			(end -0.67945 -0.305054)
			(stroke
				(width 0.1)
				(type default)
			)
			(layer "F.Fab")
		)
		(fp_line
			(start -0.67945 -0.305054)
			(end -0.12065 -0.305054)
			(stroke
				(width 0.1)
				(type default)
			)
			(layer "F.Fab")
		)
		(pad "1" smd circle
			(at -0.40005 0 180)
			(size 0 0)
			(layers "F.Cu" "F.Mask" "F.Paste")
			(net "HSC_CS_2")
		)
		(pad "2" smd circle
			(at 0.40005 0 180)
			(size 0 0)
			(layers "F.Cu" "F.Mask" "F.Paste")
			(net "AGND_HSC")
		)
	)
)
